(kicad_pcb
	(version 20260206)
	(generator "pcbnew")
	(generator_version "10.0")
	(general
		(thickness 1.6)
		(legacy_teardrops no)
	)
	(paper "A4")
	(title_block
		(title "03242023_DA0F0TMBIJ0_F0T_Motherboard_J_brd_V01_OCP.brd")
		(comment 1 "Grand Teton / footprints 568-573 of 6105")
	)
	(layers
		(0 "F.Cu" signal "TOP")
		(4 "In1.Cu" signal "GND")
		(6 "In2.Cu" signal "IN1")
		(8 "In3.Cu" signal "GND1")
		(10 "In4.Cu" signal "IN2")
		(12 "In5.Cu" signal "GND2")
		(14 "In6.Cu" signal "IN3")
		(16 "In7.Cu" signal "GND3")
		(18 "In8.Cu" signal "VCC")
		(20 "In9.Cu" signal "VCC1")
		(22 "In10.Cu" signal "GND4")
		(24 "In11.Cu" signal "IN4")
		(26 "In12.Cu" signal "GND5")
		(28 "In13.Cu" signal "IN5")
		(30 "In14.Cu" signal "GND6")
		(32 "In15.Cu" signal "IN6")
		(34 "In16.Cu" signal "GND7")
		(2 "B.Cu" signal "BOTTOM")
		(9 "F.Adhes" user "F.Adhesive")
		(11 "B.Adhes" user "B.Adhesive")
		(13 "F.Paste" user "Package Geometry/Pastemask Top")
		(15 "B.Paste" user "Package Geometry/Pastemask Bottom")
		(5 "F.SilkS" user "Ref Des/Silkscreen Top")
		(7 "B.SilkS" user "Ref Des/Silkscreen Bottom")
		(1 "F.Mask" user "Board Geometry/Soldermask Top")
		(3 "B.Mask" user "Board Geometry/Soldermask Bottom")
		(17 "Dwgs.User" user "User.Drawings")
		(19 "Cmts.User" user "User.Comments")
		(21 "Eco1.User" user "User.Eco1")
		(23 "Eco2.User" user "User.Eco2")
		(25 "Edge.Cuts" user "Board Geometry/Outline")
		(27 "Margin" user)
		(31 "F.CrtYd" user "Package Geometry/Place Bound Top")
		(29 "B.CrtYd" user "Package Geometry/Place Bound Bottom")
		(35 "F.Fab" user "Ref Des/Assembly Top")
		(33 "B.Fab" user "Ref Des/Assembly Bottom")
	)
	(footprint ""
		(layer "F.Cu")
		(at 420.682166 -133.114034 180)
		(property "Reference" "PC223"
			(at 0 0 180)
			(layer "F.SilkS")
			(hide yes)
			(effects
				(font
					(size 1.27 1.27)
				)
			)
		)
		(property "Value" ""
			(at 0 0 180)
			(layer "F.Fab")
			(effects
				(font
					(size 1.27 1.27)
				)
			)
		)
		(duplicate_pad_numbers_are_jumpers no)
		(fp_line
			(start 0.7874 0.4064)
			(end -0.7874 0.4064)
			(stroke
				(width 0.1524)
				(type default)
			)
			(layer "F.SilkS")
		)
		(fp_line
			(start 0.7874 -0.4064)
			(end 0.7874 0.4064)
			(stroke
				(width 0.1524)
				(type default)
			)
			(layer "F.SilkS")
		)
		(fp_line
			(start -0.7874 0.4064)
			(end -0.7874 -0.4064)
			(stroke
				(width 0.1524)
				(type default)
			)
			(layer "F.SilkS")
		)
		(fp_line
			(start -0.7874 -0.4064)
			(end 0.7874 -0.4064)
			(stroke
				(width 0.1524)
				(type default)
			)
			(layer "F.SilkS")
		)
		(fp_line
			(start 0.67945 0.3048)
			(end 0.120396 0.3048)
			(stroke
				(width 0.1)
				(type default)
			)
			(layer "F.Fab")
		)
		(fp_line
			(start 0.67945 -0.3048)
			(end 0.67945 0.3048)
			(stroke
				(width 0.1)
				(type default)
			)
			(layer "F.Fab")
		)
		(fp_line
			(start 0.12065 -0.2794)
			(end 0.12065 -0.3048)
			(stroke
				(width 0.1)
				(type default)
			)
			(layer "F.Fab")
		)
		(fp_line
			(start 0.12065 -0.3048)
			(end 0.67945 -0.3048)
			(stroke
				(width 0.1)
				(type default)
			)
			(layer "F.Fab")
		)
		(fp_line
			(start 0.120396 0.3048)
			(end 0.120396 0.2794)
			(stroke
				(width 0.1)
				(type default)
			)
			(layer "F.Fab")
		)
		(fp_line
			(start 0.120396 0.2794)
			(end -0.12065 0.2794)
			(stroke
				(width 0.1)
				(type default)
			)
			(layer "F.Fab")
		)
		(fp_line
			(start -0.12065 0.3048)
			(end -0.67945 0.3048)
			(stroke
				(width 0.1)
				(type default)
			)
			(layer "F.Fab")
		)
		(fp_line
			(start -0.12065 0.2794)
			(end -0.12065 0.3048)
			(stroke
				(width 0.1)
				(type default)
			)
			(layer "F.Fab")
		)
		(fp_line
			(start -0.12065 -0.2794)
			(end 0.12065 -0.2794)
			(stroke
				(width 0.1)
				(type default)
			)
			(layer "F.Fab")
		)
		(fp_line
			(start -0.12065 -0.305054)
			(end -0.12065 -0.2794)
			(stroke
				(width 0.1)
				(type default)
			)
			(layer "F.Fab")
		)
		(fp_line
			(start -0.67945 0.3048)
			(end -0.67945 -0.305054)
			(stroke
				(width 0.1)
				(type default)
			)
			(layer "F.Fab")
		)
		(fp_line
			(start -0.67945 -0.305054)
			(end -0.12065 -0.305054)
			(stroke
				(width 0.1)
				(type default)
			)
			(layer "F.Fab")
		)
		(pad "1" smd circle
			(at -0.40005 0 180)
			(size 0 0)
			(layers "F.Cu" "F.Mask" "F.Paste")
			(net "PVCCINFAON_CPU0_VCC")
		)
		(pad "2" smd circle
			(at 0.40005 0 180)
			(size 0 0)
			(layers "F.Cu" "F.Mask" "F.Paste")
			(net "GND")
		)
	)
	(footprint ""
		(layer "F.Cu")
		(at 120.187974 -338.86013)
		(property "Reference" "PR297"
			(at 0 0 0)
			(layer "F.SilkS")
			(hide yes)
			(effects
				(font
					(size 1.27 1.27)
				)
			)
		)
		(property "Value" ""
			(at 0 0 0)
			(layer "F.Fab")
			(effects
				(font
					(size 1.27 1.27)
				)
			)
		)
		(duplicate_pad_numbers_are_jumpers no)
		(fp_line
			(start -0.7874 -0.4064)
			(end 0.7874 -0.4064)
			(stroke
				(width 0.1524)
				(type default)
			)
			(layer "F.SilkS")
		)
		(fp_line
			(start -0.7874 0.4064)
			(end -0.7874 -0.4064)
			(stroke
				(width 0.1524)
				(type default)
			)
			(layer "F.SilkS")
		)
		(fp_line
			(start 0.7874 -0.4064)
			(end 0.7874 0.4064)
			(stroke
				(width 0.1524)
				(type default)
			)
			(layer "F.SilkS")
		)
		(fp_line
			(start 0.7874 0.4064)
			(end -0.7874 0.4064)
			(stroke
				(width 0.1524)
				(type default)
			)
			(layer "F.SilkS")
		)
		(fp_line
			(start -0.67945 -0.305054)
			(end -0.12065 -0.305054)
			(stroke
				(width 0.1)
				(type default)
			)
			(layer "F.Fab")
		)
		(fp_line
			(start -0.67945 0.3048)
			(end -0.67945 -0.305054)
			(stroke
				(width 0.1)
				(type default)
			)
			(layer "F.Fab")
		)
		(fp_line
			(start -0.12065 -0.305054)
			(end -0.12065 -0.2794)
			(stroke
				(width 0.1)
				(type default)
			)
			(layer "F.Fab")
		)
		(fp_line
			(start -0.12065 -0.2794)
			(end 0.12065 -0.2794)
			(stroke
				(width 0.1)
				(type default)
			)
			(layer "F.Fab")
		)
		(fp_line
			(start -0.12065 0.2794)
			(end -0.12065 0.3048)
			(stroke
				(width 0.1)
				(type default)
			)
			(layer "F.Fab")
		)
		(fp_line
			(start -0.12065 0.3048)
			(end -0.67945 0.3048)
			(stroke
				(width 0.1)
				(type default)
			)
			(layer "F.Fab")
		)
		(fp_line
			(start 0.120396 0.2794)
			(end -0.12065 0.2794)
			(stroke
				(width 0.1)
				(type default)
			)
			(layer "F.Fab")
		)
		(fp_line
			(start 0.120396 0.3048)
			(end 0.120396 0.2794)
			(stroke
				(width 0.1)
				(type default)
			)
			(layer "F.Fab")
		)
		(fp_line
			(start 0.12065 -0.3048)
			(end 0.67945 -0.3048)
			(stroke
				(width 0.1)
				(type default)
			)
			(layer "F.Fab")
		)
		(fp_line
			(start 0.12065 -0.2794)
			(end 0.12065 -0.3048)
			(stroke
				(width 0.1)
				(type default)
			)
			(layer "F.Fab")
		)
		(fp_line
			(start 0.67945 -0.3048)
			(end 0.67945 0.3048)
			(stroke
				(width 0.1)
				(type default)
			)
			(layer "F.Fab")
		)
		(fp_line
			(start 0.67945 0.3048)
			(end 0.120396 0.3048)
			(stroke
				(width 0.1)
				(type default)
			)
			(layer "F.Fab")
		)
		(pad "1" smd circle
			(at -0.40005 0)
			(size 0 0)
			(layers "F.Cu" "F.Mask" "F.Paste")
			(net "PVCCIN_CPU1_LSET4")
		)
		(pad "2" smd circle
			(at 0.40005 0)
			(size 0 0)
			(layers "F.Cu" "F.Mask" "F.Paste")
			(net "GND")
		)
	)
	(footprint ""
		(layer "F.Cu")
		(at 24.71928 -176.850548 180)
		(property "Reference" "PC28"
			(at 0 0 180)
			(layer "F.SilkS")
			(hide yes)
			(effects
				(font
					(size 1.27 1.27)
				)
			)
		)
		(property "Value" ""
			(at 0 0 180)
			(layer "F.Fab")
			(effects
				(font
					(size 1.27 1.27)
				)
			)
		)
		(duplicate_pad_numbers_are_jumpers no)
		(fp_line
			(start 0.7874 0.4064)
			(end -0.7874 0.4064)
			(stroke
				(width 0.1524)
				(type default)
			)
			(layer "F.SilkS")
		)
		(fp_line
			(start 0.7874 -0.4064)
			(end 0.7874 0.4064)
			(stroke
				(width 0.1524)
				(type default)
			)
			(layer "F.SilkS")
		)
		(fp_line
			(start -0.7874 0.4064)
			(end -0.7874 -0.4064)
			(stroke
				(width 0.1524)
				(type default)
			)
			(layer "F.SilkS")
		)
		(fp_line
			(start -0.7874 -0.4064)
			(end 0.7874 -0.4064)
			(stroke
				(width 0.1524)
				(type default)
			)
			(layer "F.SilkS")
		)
		(fp_line
			(start 0.67945 0.3048)
			(end 0.120396 0.3048)
			(stroke
				(width 0.1)
				(type default)
			)
			(layer "F.Fab")
		)
		(fp_line
			(start 0.67945 -0.3048)
			(end 0.67945 0.3048)
			(stroke
				(width 0.1)
				(type default)
			)
			(layer "F.Fab")
		)
		(fp_line
			(start 0.12065 -0.2794)
			(end 0.12065 -0.3048)
			(stroke
				(width 0.1)
				(type default)
			)
			(layer "F.Fab")
		)
		(fp_line
			(start 0.12065 -0.3048)
			(end 0.67945 -0.3048)
			(stroke
				(width 0.1)
				(type default)
			)
			(layer "F.Fab")
		)
		(fp_line
			(start 0.120396 0.3048)
			(end 0.120396 0.2794)
			(stroke
				(width 0.1)
				(type default)
			)
			(layer "F.Fab")
		)
		(fp_line
			(start 0.120396 0.2794)
			(end -0.12065 0.2794)
			(stroke
				(width 0.1)
				(type default)
			)
			(layer "F.Fab")
		)
		(fp_line
			(start -0.12065 0.3048)
			(end -0.67945 0.3048)
			(stroke
				(width 0.1)
				(type default)
			)
			(layer "F.Fab")
		)
		(fp_line
			(start -0.12065 0.2794)
			(end -0.12065 0.3048)
			(stroke
				(width 0.1)
				(type default)
			)
			(layer "F.Fab")
		)
		(fp_line
			(start -0.12065 -0.2794)
			(end 0.12065 -0.2794)
			(stroke
				(width 0.1)
				(type default)
			)
			(layer "F.Fab")
		)
		(fp_line
			(start -0.12065 -0.305054)
			(end -0.12065 -0.2794)
			(stroke
				(width 0.1)
				(type default)
			)
			(layer "F.Fab")
		)
		(fp_line
			(start -0.67945 0.3048)
			(end -0.67945 -0.305054)
			(stroke
				(width 0.1)
				(type default)
			)
			(layer "F.Fab")
		)
		(fp_line
			(start -0.67945 -0.305054)
			(end -0.12065 -0.305054)
			(stroke
				(width 0.1)
				(type default)
			)
			(layer "F.Fab")
		)
		(pad "1" smd circle
			(at -0.40005 0 180)
			(size 0 0)
			(layers "F.Cu" "F.Mask" "F.Paste")
			(net "PVNN_MAIN_CPU1_REF")
		)
		(pad "2" smd circle
			(at 0.40005 0 180)
			(size 0 0)
			(layers "F.Cu" "F.Mask" "F.Paste")
			(net "GND")
		)
	)
	(footprint ""
		(layer "F.Cu")
		(at 80.681068 -333.61884)
		(property "Reference" "PL25"
			(at -2.416556 6.896354 0)
			(unlocked yes)
			(layer "F.SilkS")
			(effects
				(font
					(size 0.7874 0.5842)
					(thickness 0.1524)
				)
				(justify left)
			)
		)
		(property "Value" ""
			(at 0 0 0)
			(layer "F.Fab")
			(effects
				(font
					(size 1.27 1.27)
				)
			)
		)
		(duplicate_pad_numbers_are_jumpers no)
		(fp_line
			(start -3.750056 -5.500116)
			(end -2.393442 -5.500116)
			(stroke
				(width 0.1524)
				(type default)
			)
			(layer "F.SilkS")
		)
		(fp_line
			(start -3.750056 5.500116)
			(end -3.750056 -5.500116)
			(stroke
				(width 0.1524)
				(type default)
			)
			(layer "F.SilkS")
		)
		(fp_line
			(start -2.393442 5.500116)
			(end -3.750056 5.500116)
			(stroke
				(width 0.1524)
				(type default)
			)
			(layer "F.SilkS")
		)
		(fp_line
			(start 2.393442 5.500116)
			(end 3.750056 5.500116)
			(stroke
				(width 0.1524)
				(type default)
			)
			(layer "F.SilkS")
		)
		(fp_line
			(start 3.750056 -5.500116)
			(end 2.393442 -5.500116)
			(stroke
				(width 0.1524)
				(type default)
			)
			(layer "F.SilkS")
		)
		(fp_line
			(start 3.750056 5.500116)
			(end 3.750056 -5.500116)
			(stroke
				(width 0.1524)
				(type default)
			)
			(layer "F.SilkS")
		)
		(fp_poly
			(pts
				(xy -3.607054 -7.02945) (xy -3.247898 -5.951728) (xy -4.32562 -6.310884)
			)
			(stroke
				(width 0)
				(type default)
			)
			(fill yes)
			(layer "F.SilkS")
		)
		(fp_line
			(start -3.750056 -5.500116)
			(end -3.750056 5.500116)
			(stroke
				(width 0.1)
				(type default)
			)
			(layer "F.Fab")
		)
		(fp_line
			(start -3.750056 5.500116)
			(end 3.750056 5.500116)
			(stroke
				(width 0.1)
				(type default)
			)
			(layer "F.Fab")
		)
		(fp_line
			(start 3.750056 -5.500116)
			(end -3.750056 -5.500116)
			(stroke
				(width 0.1)
				(type default)
			)
			(layer "F.Fab")
		)
		(fp_line
			(start 3.750056 5.500116)
			(end 3.750056 -5.500116)
			(stroke
				(width 0.1)
				(type default)
			)
			(layer "F.Fab")
		)
		(fp_poly
			(pts
				(xy -4.9276 -4.757928) (xy -4.9276 -3.741928) (xy -3.9116 -4.249928)
			)
			(stroke
				(width 0)
				(type default)
			)
			(fill yes)
			(layer "F.Fab")
		)
		(pad "1" smd rect
			(at 0 -4.249928 270)
			(size 2.413 4.5212)
			(layers "F.Cu" "F.Mask" "F.Paste")
			(net "SW_PVCCIN_CPU1_SW7")
		)
		(pad "2" smd rect
			(at 0 -1.175004 270)
			(size 1.3716 4.5212)
			(layers "F.Cu" "F.Mask" "F.Paste")
			(net "IND_P1_CPL7")
		)
		(pad "3" smd rect
			(at 0 1.175004 270)
			(size 1.3716 4.5212)
			(layers "F.Cu" "F.Mask" "F.Paste")
			(net "GND")
		)
		(pad "4" smd rect
			(at 0 4.249928 270)
			(size 2.413 4.5212)
			(layers "F.Cu" "F.Mask" "F.Paste")
			(net "PVCCIN_CPU1")
		)
	)
	(footprint ""
		(layer "F.Cu")
		(at 448.478402 -77.829918 90)
		(property "Reference" "PR831"
			(at 0 0 90)
			(layer "F.SilkS")
			(hide yes)
			(effects
				(font
					(size 1.27 1.27)
				)
			)
		)
		(property "Value" ""
			(at 0 0 90)
			(layer "F.Fab")
			(effects
				(font
					(size 1.27 1.27)
				)
			)
		)
		(duplicate_pad_numbers_are_jumpers no)
		(fp_line
			(start 0.7874 -0.4064)
			(end 0.7874 0.4064)
			(stroke
				(width 0.1524)
				(type default)
			)
			(layer "F.SilkS")
		)
		(fp_line
			(start -0.7874 -0.4064)
			(end 0.7874 -0.4064)
			(stroke
				(width 0.1524)
				(type default)
			)
			(layer "F.SilkS")
		)
		(fp_line
			(start 0.7874 0.4064)
			(end -0.7874 0.4064)
			(stroke
				(width 0.1524)
				(type default)
			)
			(layer "F.SilkS")
		)
		(fp_line
			(start -0.7874 0.4064)
			(end -0.7874 -0.4064)
			(stroke
				(width 0.1524)
				(type default)
			)
			(layer "F.SilkS")
		)
		(fp_line
			(start -0.12065 -0.305054)
			(end -0.12065 -0.2794)
			(stroke
				(width 0.1)
				(type default)
			)
			(layer "F.Fab")
		)
		(fp_line
			(start -0.67945 -0.305054)
			(end -0.12065 -0.305054)
			(stroke
				(width 0.1)
				(type default)
			)
			(layer "F.Fab")
		)
		(fp_line
			(start 0.67945 -0.3048)
			(end 0.67945 0.3048)
			(stroke
				(width 0.1)
				(type default)
			)
			(layer "F.Fab")
		)
		(fp_line
			(start 0.12065 -0.3048)
			(end 0.67945 -0.3048)
			(stroke
				(width 0.1)
				(type default)
			)
			(layer "F.Fab")
		)
		(fp_line
			(start 0.12065 -0.2794)
			(end 0.12065 -0.3048)
			(stroke
				(width 0.1)
				(type default)
			)
			(layer "F.Fab")
		)
		(fp_line
			(start -0.12065 -0.2794)
			(end 0.12065 -0.2794)
			(stroke
				(width 0.1)
				(type default)
			)
			(layer "F.Fab")
		)
		(fp_line
			(start 0.120396 0.2794)
			(end -0.12065 0.2794)
			(stroke
				(width 0.1)
				(type default)
			)
			(layer "F.Fab")
		)
		(fp_line
			(start -0.12065 0.2794)
			(end -0.12065 0.3048)
			(stroke
				(width 0.1)
				(type default)
			)
			(layer "F.Fab")
		)
		(fp_line
			(start 0.67945 0.3048)
			(end 0.120396 0.3048)
			(stroke
				(width 0.1)
				(type default)
			)
			(layer "F.Fab")
		)
		(fp_line
			(start 0.120396 0.3048)
			(end 0.120396 0.2794)
			(stroke
				(width 0.1)
				(type default)
			)
			(layer "F.Fab")
		)
		(fp_line
			(start -0.12065 0.3048)
			(end -0.67945 0.3048)
			(stroke
				(width 0.1)
				(type default)
			)
			(layer "F.Fab")
		)
		(fp_line
			(start -0.67945 0.3048)
			(end -0.67945 -0.305054)
			(stroke
				(width 0.1)
				(type default)
			)
			(layer "F.Fab")
		)
		(pad "1" smd circle
			(at -0.40005 0 90)
			(size 0 0)
			(layers "F.Cu" "F.Mask" "F.Paste")
			(net "P3V3_AUX_FB")
		)
		(pad "2" smd circle
			(at 0.40005 0 90)
			(size 0 0)
			(layers "F.Cu" "F.Mask" "F.Paste")
			(net "P3V3_AUX")
		)
	)
	(footprint ""
		(layer "F.Cu")
		(at 131.466844 -127.119126 180)
		(property "Reference" "R2985"
			(at 0 0 180)
			(layer "F.SilkS")
			(hide yes)
			(effects
				(font
					(size 1.27 1.27)
				)
			)
		)
		(property "Value" ""
			(at 0 0 180)
			(layer "F.Fab")
			(effects
				(font
					(size 1.27 1.27)
				)
			)
		)
		(duplicate_pad_numbers_are_jumpers no)
		(fp_line
			(start 0.7874 0.4064)
			(end -0.7874 0.4064)
			(stroke
				(width 0.1524)
				(type default)
			)
			(layer "F.SilkS")
		)
		(fp_line
			(start 0.7874 -0.4064)
			(end 0.7874 0.4064)
			(stroke
				(width 0.1524)
				(type default)
			)
			(layer "F.SilkS")
		)
		(fp_line
			(start -0.7874 0.4064)
			(end -0.7874 -0.4064)
			(stroke
				(width 0.1524)
				(type default)
			)
			(layer "F.SilkS")
		)
		(fp_line
			(start -0.7874 -0.4064)
			(end 0.7874 -0.4064)
			(stroke
				(width 0.1524)
				(type default)
			)
			(layer "F.SilkS")
		)
		(fp_line
			(start 0.67945 0.3048)
			(end 0.120396 0.3048)
			(stroke
				(width 0.1)
				(type default)
			)
			(layer "F.Fab")
		)
		(fp_line
			(start 0.67945 -0.3048)
			(end 0.67945 0.3048)
			(stroke
				(width 0.1)
				(type default)
			)
			(layer "F.Fab")
		)
		(fp_line
			(start 0.12065 -0.2794)
			(end 0.12065 -0.3048)
			(stroke
				(width 0.1)
				(type default)
			)
			(layer "F.Fab")
		)
		(fp_line
			(start 0.12065 -0.3048)
			(end 0.67945 -0.3048)
			(stroke
				(width 0.1)
				(type default)
			)
			(layer "F.Fab")
		)
		(fp_line
			(start 0.120396 0.3048)
			(end 0.120396 0.2794)
			(stroke
				(width 0.1)
				(type default)
			)
			(layer "F.Fab")
		)
		(fp_line
			(start 0.120396 0.2794)
			(end -0.12065 0.2794)
			(stroke
				(width 0.1)
				(type default)
			)
			(layer "F.Fab")
		)
		(fp_line
			(start -0.12065 0.3048)
			(end -0.67945 0.3048)
			(stroke
				(width 0.1)
				(type default)
			)
			(layer "F.Fab")
		)
		(fp_line
			(start -0.12065 0.2794)
			(end -0.12065 0.3048)
			(stroke
				(width 0.1)
				(type default)
			)
			(layer "F.Fab")
		)
		(fp_line
			(start -0.12065 -0.2794)
			(end 0.12065 -0.2794)
			(stroke
				(width 0.1)
				(type default)
			)
			(layer "F.Fab")
		)
		(fp_line
			(start -0.12065 -0.305054)
			(end -0.12065 -0.2794)
			(stroke
				(width 0.1)
				(type default)
			)
			(layer "F.Fab")
		)
		(fp_line
			(start -0.67945 0.3048)
			(end -0.67945 -0.305054)
			(stroke
				(width 0.1)
				(type default)
			)
			(layer "F.Fab")
		)
		(fp_line
			(start -0.67945 -0.305054)
			(end -0.12065 -0.305054)
			(stroke
				(width 0.1)
				(type default)
			)
			(layer "F.Fab")
		)
		(pad "1" smd circle
			(at -0.40005 0 180)
			(size 0 0)
			(layers "F.Cu" "F.Mask" "F.Paste")
			(net "P3V3_AUX")
		)
		(pad "2" smd circle
			(at 0.40005 0 180)
			(size 0 0)
			(layers "F.Cu" "F.Mask" "F.Paste")
			(net "SMB_BMC_SWB_SDA")
		)
	)
)
